(kicad_pcb
	(version 20260206)
	(generator "pcbnew")
	(generator_version "10.0")
	(general
		(thickness 1.6)
		(legacy_teardrops no)
	)
	(paper "A4")
	(title_block
		(title "Bryce Canyon_R.DPB_16317-1_OCP.brd")
		(comment 1 "Bryce Canyon / footprints 1769-1776 of 2099")
	)
	(layers
		(0 "F.Cu" signal "TOP")
		(4 "In1.Cu" signal "L2GND")
		(6 "In2.Cu" signal "L3")
		(8 "In3.Cu" signal "L4VCC")
		(10 "In4.Cu" signal "L5VCC")
		(12 "In5.Cu" signal "L6")
		(14 "In6.Cu" signal "L7GND")
		(2 "B.Cu" signal "BOTTOM")
		(9 "F.Adhes" user "F.Adhesive")
		(11 "B.Adhes" user "B.Adhesive")
		(13 "F.Paste" user "Package Geometry/Pastemask Top")
		(15 "B.Paste" user "Package Geometry/Pastemask Bottom")
		(5 "F.SilkS" user "Ref Des/Silkscreen Top")
		(7 "B.SilkS" user "Ref Des/Silkscreen Bottom")
		(1 "F.Mask" user "Board Geometry/Soldermask Top")
		(3 "B.Mask" user "Board Geometry/Soldermask Bottom")
		(17 "Dwgs.User" user "User.Drawings")
		(19 "Cmts.User" user "User.Comments")
		(21 "Eco1.User" user "User.Eco1")
		(23 "Eco2.User" user "User.Eco2")
		(25 "Edge.Cuts" user "Board Geometry/Outline")
		(27 "Margin" user)
		(31 "F.CrtYd" user "Package Geometry/Place Bound Top")
		(29 "B.CrtYd" user "Package Geometry/Place Bound Bottom")
		(35 "F.Fab" user "Ref Des/Assembly Top")
		(33 "B.Fab" user "Ref Des/Assembly Bottom")
	)
	(footprint ""
		(layer "F.Cu")
		(at 346.700094 -65.39992)
		(property "Reference" "LED20"
			(at 0 0 0)
			(layer "F.SilkS")
			(hide yes)
			(effects
				(font
					(size 1.27 1.27)
				)
			)
		)
		(property "Value" "LED-BY-19-GP"
			(at -2.132076 1.414018 0)
			(unlocked yes)
			(layer "F.Fab")
			(hide yes)
			(effects
				(font
					(size 1.016 1.016)
					(thickness 0.1524)
				)
			)
		)
		(property "Device Type" "LED-1615-4PH26"
			(at -2.132076 -0.109982 0)
			(unlocked yes)
			(layer "F.Fab")
			(hide yes)
			(effects
				(font
					(size 1.016 1.016)
					(thickness 0.1524)
				)
			)
		)
		(duplicate_pad_numbers_are_jumpers no)
		(fp_line
			(start -1.2954 0.254)
			(end -1.2954 1.6002)
			(stroke
				(width 0.508)
				(type default)
			)
			(layer "F.SilkS")
		)
		(fp_line
			(start -1.2954 1.6002)
			(end 1.2954 1.6002)
			(stroke
				(width 0.508)
				(type default)
			)
			(layer "F.SilkS")
		)
		(fp_line
			(start -1.1176 -1.4224)
			(end 1.1176 -1.4224)
			(stroke
				(width 0.1524)
				(type default)
			)
			(layer "F.SilkS")
		)
		(fp_line
			(start -1.1176 1.4224)
			(end -1.1176 -1.4224)
			(stroke
				(width 0.1524)
				(type default)
			)
			(layer "F.SilkS")
		)
		(fp_line
			(start 1.1176 -1.4224)
			(end 1.1176 1.4224)
			(stroke
				(width 0.1524)
				(type default)
			)
			(layer "F.SilkS")
		)
		(fp_line
			(start 1.1176 1.4224)
			(end -1.1176 1.4224)
			(stroke
				(width 0.1524)
				(type default)
			)
			(layer "F.SilkS")
		)
		(fp_line
			(start 1.2954 1.6002)
			(end 1.2954 0.254)
			(stroke
				(width 0.508)
				(type default)
			)
			(layer "F.SilkS")
		)
		(fp_rect
			(start -0.7493 0.8001)
			(end 0.7493 -0.8001)
			(stroke
				(width 0)
				(type default)
			)
			(fill no)
			(layer "F.CrtYd")
		)
		(fp_poly
			(pts
				(xy -1.3716 1.6764) (xy -1.3716 -1.6764) (xy 1.3716 -1.6764) (xy 1.3716 0.0635) (xy 0.7493 0.0635)
				(xy 0.7493 -0.8001) (xy -0.7493 -0.8001) (xy -0.7493 0.8001) (xy 0.7493 0.8001) (xy 0.7493 0.0762)
				(xy 1.3716 0.0762) (xy 1.3716 1.6764)
			)
			(stroke
				(width 0)
				(type default)
			)
			(fill no)
			(layer "F.CrtYd")
		)
		(fp_rect
			(start -1.3716 1.6764)
			(end 1.3716 -1.6764)
			(stroke
				(width 0)
				(type default)
			)
			(fill no)
			(layer "F.Fab")
		)
		(pad "1" smd rect
			(at 0.50038 -0.73025)
			(size 0.7112 0.8636)
			(layers "F.Cu" "F.Mask" "F.Paste")
			(net "DRV_ACT_19")
		)
		(pad "2" smd rect
			(at -0.50038 -0.73025)
			(size 0.7112 0.8636)
			(layers "F.Cu" "F.Mask" "F.Paste")
			(net "FLT_HDD19")
		)
		(pad "3" smd rect
			(at 0.50038 0.73025)
			(size 0.7112 0.8636)
			(layers "F.Cu" "F.Mask" "F.Paste")
			(net "DRV_ACT_19_N")
		)
		(pad "4" smd rect
			(at -0.50038 0.73025)
			(size 0.7112 0.8636)
			(layers "F.Cu" "F.Mask" "F.Paste")
			(net "FLT_HDD19_N")
		)
	)
	(footprint ""
		(layer "F.Cu")
		(at 172.466 -35.687 -90)
		(property "Reference" "C411"
			(at 0 0 270)
			(layer "F.SilkS")
			(hide yes)
			(effects
				(font
					(size 1.27 1.27)
				)
			)
		)
		(property "Value" "SC4D7U25V5KX-1-GP"
			(at -0.0762 -6.1214 270)
			(unlocked yes)
			(layer "F.Fab")
			(hide yes)
			(effects
				(font
					(size 1.016 1.016)
					(thickness 0.1524)
				)
			)
		)
		(property "Device Type" "C805H58"
			(at -0.0762 -8.1534 270)
			(unlocked yes)
			(layer "F.Fab")
			(hide yes)
			(effects
				(font
					(size 1.016 1.016)
					(thickness 0.1524)
				)
			)
		)
		(duplicate_pad_numbers_are_jumpers no)
		(fp_line
			(start 0.635 0)
			(end -0.635 0)
			(stroke
				(width 0.508)
				(type default)
			)
			(layer "F.SilkS")
		)
		(fp_rect
			(start -0.9652 1.778)
			(end 0.9652 -1.778)
			(stroke
				(width 0)
				(type default)
			)
			(fill no)
			(layer "F.CrtYd")
		)
		(fp_poly
			(pts
				(xy -0.9652 -1.778) (xy 0.9652 -1.778) (xy 0.9652 1.778) (xy -0.9652 1.778)
			)
			(stroke
				(width 0)
				(type default)
			)
			(fill no)
			(layer "F.Fab")
		)
		(pad "1" smd rect
			(at 0 -0.9652 270)
			(size 1.397 1.143)
			(layers "F.Cu" "F.Mask" "F.Paste")
			(net "P12V_HDD29")
		)
		(pad "2" smd rect
			(at 0 0.9652 270)
			(size 1.397 1.143)
			(layers "F.Cu" "F.Mask" "F.Paste")
			(net "GND")
		)
	)
	(footprint ""
		(layer "F.Cu")
		(at 414.436052 -13.6271 180)
		(property "Reference" "VIA67"
			(at 0 0 180)
			(layer "F.SilkS")
			(hide yes)
			(effects
				(font
					(size 1.27 1.27)
				)
			)
		)
		(property "Value" "100OHM-8L-2D36MM-L18-GP"
			(at 3.8989 0.5715 180)
			(unlocked yes)
			(layer "F.Fab")
			(hide yes)
			(effects
				(font
					(size 1.016 1.016)
					(thickness 0.1524)
				)
			)
		)
		(property "Device Type" "VIA-PCIE-4P-414097"
			(at 3.8989 -0.9525 180)
			(unlocked yes)
			(layer "F.Fab")
			(hide yes)
			(effects
				(font
					(size 1.016 1.016)
					(thickness 0.1524)
				)
			)
		)
		(duplicate_pad_numbers_are_jumpers no)
		(fp_rect
			(start -2.0701 0.4826)
			(end 2.0701 -0.4826)
			(stroke
				(width 0)
				(type default)
			)
			(fill no)
			(layer "F.CrtYd")
		)
		(fp_rect
			(start -2.0701 0.4826)
			(end 2.0701 -0.4826)
			(stroke
				(width 0)
				(type default)
			)
			(fill no)
			(layer "F.Fab")
		)
		(pad "1" thru_hole circle
			(at -1.5875 0 180)
			(size 0.508 0.508)
			(drill 0.254)
			(layers "*.Cu" "*.Mask")
			(remove_unused_layers no)
			(net "GND")
			(clearance 0.2286)
			(thermal_gap 0.2286)
		)
		(pad "2" thru_hole circle
			(at -0.5715 0 180)
			(size 0.508 0.508)
			(drill 0.254)
			(layers "*.Cu" "*.Mask")
			(remove_unused_layers no)
			(net "PHY_SCC_B_TO_DRV_B_33_DP")
			(clearance 0.2286)
			(thermal_gap 0.2286)
		)
		(pad "3" thru_hole circle
			(at 0.5715 0 180)
			(size 0.508 0.508)
			(drill 0.254)
			(layers "*.Cu" "*.Mask")
			(remove_unused_layers no)
			(net "PHY_SCC_B_TO_DRV_B_33_DN")
			(clearance 0.2286)
			(thermal_gap 0.2286)
		)
		(pad "4" thru_hole circle
			(at 1.5875 0 180)
			(size 0.508 0.508)
			(drill 0.254)
			(layers "*.Cu" "*.Mask")
			(remove_unused_layers no)
			(net "GND")
			(clearance 0.2286)
			(thermal_gap 0.2286)
		)
	)
	(footprint ""
		(layer "F.Cu")
		(at 449.5165 -17.4371)
		(property "Reference" "VIA70"
			(at 0 0 0)
			(layer "F.SilkS")
			(hide yes)
			(effects
				(font
					(size 1.27 1.27)
				)
			)
		)
		(property "Value" "100OHM-8L-2D36MM-L16-GP"
			(at -3.4036 -0.4572 0)
			(unlocked yes)
			(layer "F.Fab")
			(hide yes)
			(effects
				(font
					(size 1.016 1.016)
					(thickness 0.1524)
				)
			)
		)
		(property "Device Type" "VIA-PCIE-4P-427097"
			(at -3.4036 -1.9812 0)
			(unlocked yes)
			(layer "F.Fab")
			(hide yes)
			(effects
				(font
					(size 1.016 1.016)
					(thickness 0.1524)
				)
			)
		)
		(duplicate_pad_numbers_are_jumpers no)
		(fp_rect
			(start -2.1336 0.4826)
			(end 2.1336 -0.4826)
			(stroke
				(width 0)
				(type default)
			)
			(fill no)
			(layer "F.CrtYd")
		)
		(fp_rect
			(start -2.1336 0.4826)
			(end 2.1336 -0.4826)
			(stroke
				(width 0)
				(type default)
			)
			(fill no)
			(layer "F.Fab")
		)
		(pad "1" thru_hole circle
			(at -1.651 0)
			(size 0.508 0.508)
			(drill 0.254)
			(layers "*.Cu" "*.Mask")
			(remove_unused_layers no)
			(net "GND")
			(clearance 0.2286)
			(thermal_gap 0.2286)
		)
		(pad "2" thru_hole circle
			(at -0.635 0)
			(size 0.508 0.508)
			(drill 0.254)
			(layers "*.Cu" "*.Mask")
			(remove_unused_layers no)
			(net "PHY_DRV_B_TO_SCC_B_34_DP")
			(clearance 0.2286)
			(thermal_gap 0.2286)
		)
		(pad "3" thru_hole circle
			(at 0.635 0)
			(size 0.508 0.508)
			(drill 0.254)
			(layers "*.Cu" "*.Mask")
			(remove_unused_layers no)
			(net "PHY_DRV_B_TO_SCC_B_34_DN")
			(clearance 0.2286)
			(thermal_gap 0.2286)
		)
		(pad "4" thru_hole circle
			(at 1.651 0)
			(size 0.508 0.508)
			(drill 0.254)
			(layers "*.Cu" "*.Mask")
			(remove_unused_layers no)
			(net "GND")
			(clearance 0.2286)
			(thermal_gap 0.2286)
		)
	)
	(footprint ""
		(layer "F.Cu")
		(at 165.42893 -365.358426)
		(property "Reference" "C551"
			(at 0 0 0)
			(layer "F.SilkS")
			(hide yes)
			(effects
				(font
					(size 1.27 1.27)
				)
			)
		)
		(property "Value" "SC1U16V3KX-5GP"
			(at 0 -2.8194 0)
			(unlocked yes)
			(layer "F.Fab")
			(hide yes)
			(effects
				(font
					(size 1.016 1.016)
					(thickness 0.1524)
				)
			)
		)
		(property "Device Type" "C603H36"
			(at 0 -4.3434 0)
			(unlocked yes)
			(layer "F.Fab")
			(hide yes)
			(effects
				(font
					(size 1.016 1.016)
					(thickness 0.1524)
				)
			)
		)
		(duplicate_pad_numbers_are_jumpers no)
		(fp_line
			(start 0.508 0)
			(end -0.508 0)
			(stroke
				(width 0.2032)
				(type default)
			)
			(layer "F.SilkS")
		)
		(fp_rect
			(start -0.5842 1.3335)
			(end 0.5842 -1.3335)
			(stroke
				(width 0)
				(type default)
			)
			(fill no)
			(layer "F.CrtYd")
		)
		(fp_rect
			(start -0.5842 1.3335)
			(end 0.5842 -1.3335)
			(stroke
				(width 0)
				(type default)
			)
			(fill no)
			(layer "F.Fab")
		)
		(pad "1" smd custom
			(at 0 -0.762)
			(size 0.2159 0.2159)
			(layers "F.Cu" "F.Mask" "F.Paste")
			(net "MB0_CM_UV_R")
			(options
				(clearance outline)
				(anchor circle)
			)
			(primitives
				(gr_poly
					(pts
						(arc
							(start -0.3302 -0.4318)
							(mid -0.402042 -0.402042)
							(end -0.4318 -0.3302)
						)
						(arc
							(start -0.4318 0.3302)
							(mid -0.402042 0.402042)
							(end -0.3302 0.4318)
						)
						(arc
							(start 0.3302 0.4318)
							(mid 0.402042 0.402042)
							(end 0.4318 0.3302)
						)
						(arc
							(start 0.4318 -0.3302)
							(mid 0.402042 -0.402042)
							(end 0.3302 -0.4318)
						)
					)
					(width 0)
					(fill yes)
				)
			)
		)
		(pad "2" smd custom
			(at 0 0.762)
			(size 0.2159 0.2159)
			(layers "F.Cu" "F.Mask" "F.Paste")
			(net "AGND_CURRENT_MON")
			(options
				(clearance outline)
				(anchor circle)
			)
			(primitives
				(gr_poly
					(pts
						(arc
							(start -0.3302 -0.4318)
							(mid -0.402042 -0.402042)
							(end -0.4318 -0.3302)
						)
						(arc
							(start -0.4318 0.3302)
							(mid -0.402042 0.402042)
							(end -0.3302 0.4318)
						)
						(arc
							(start 0.3302 0.4318)
							(mid 0.402042 0.402042)
							(end 0.4318 0.3302)
						)
						(arc
							(start 0.4318 -0.3302)
							(mid 0.402042 -0.402042)
							(end 0.3302 -0.4318)
						)
					)
					(width 0)
					(fill yes)
				)
			)
		)
	)
	(footprint ""
		(layer "F.Cu")
		(at 43.07586 -115.389406 -90)
		(property "Reference" "R1133"
			(at 0 0 270)
			(layer "F.SilkS")
			(hide yes)
			(effects
				(font
					(size 1.27 1.27)
				)
			)
		)
		(property "Value" "309KR2F-GP"
			(at 0.064008 -3.993896 270)
			(unlocked yes)
			(layer "F.Fab")
			(hide yes)
			(effects
				(font
					(size 1.016 1.016)
					(thickness 0.1524)
				)
			)
		)
		(property "Device Type" "R402H16"
			(at 0.064008 -5.517896 270)
			(unlocked yes)
			(layer "F.Fab")
			(hide yes)
			(effects
				(font
					(size 1.016 1.016)
					(thickness 0.1524)
				)
			)
		)
		(duplicate_pad_numbers_are_jumpers no)
		(fp_line
			(start -0.508 -0.9398)
			(end -0.508 0.9398)
			(stroke
				(width 0.1524)
				(type default)
			)
			(layer "F.SilkS")
		)
		(fp_line
			(start 0.508 -0.9398)
			(end -0.508 -0.9398)
			(stroke
				(width 0.1524)
				(type default)
			)
			(layer "F.SilkS")
		)
		(fp_rect
			(start -0.508 0.9398)
			(end 0.508 -0.9398)
			(stroke
				(width 0)
				(type default)
			)
			(fill no)
			(layer "F.CrtYd")
		)
		(fp_rect
			(start -0.508 0.9398)
			(end 0.508 -0.9398)
			(stroke
				(width 0)
				(type default)
			)
			(fill no)
			(layer "F.Fab")
		)
		(pad "1" smd custom
			(at 0 -0.4445 270)
			(size 0.1397 0.1397)
			(layers "F.Cu" "F.Mask" "F.Paste")
			(net "P5V_B_2_RF")
			(options
				(clearance outline)
				(anchor circle)
			)
			(primitives
				(gr_poly
					(pts
						(arc
							(start -0.1778 -0.2794)
							(mid -0.249642 -0.249642)
							(end -0.2794 -0.1778)
						)
						(arc
							(start -0.2794 0.1778)
							(mid -0.249642 0.249642)
							(end -0.1778 0.2794)
						)
						(arc
							(start 0.1778 0.2794)
							(mid 0.249642 0.249642)
							(end 0.2794 0.1778)
						)
						(arc
							(start 0.2794 -0.1778)
							(mid 0.249642 -0.249642)
							(end 0.1778 -0.2794)
						)
					)
					(width 0)
					(fill yes)
				)
			)
		)
		(pad "2" smd custom
			(at 0 0.4445 270)
			(size 0.1397 0.1397)
			(layers "F.Cu" "F.Mask" "F.Paste")
			(net "P5V_B_2_VREG")
			(options
				(clearance outline)
				(anchor circle)
			)
			(primitives
				(gr_poly
					(pts
						(arc
							(start -0.1778 -0.2794)
							(mid -0.249642 -0.249642)
							(end -0.2794 -0.1778)
						)
						(arc
							(start -0.2794 0.1778)
							(mid -0.249642 0.249642)
							(end -0.1778 0.2794)
						)
						(arc
							(start 0.1778 0.2794)
							(mid 0.249642 0.249642)
							(end 0.2794 0.1778)
						)
						(arc
							(start 0.2794 -0.1778)
							(mid 0.249642 -0.249642)
							(end 0.1778 -0.2794)
						)
					)
					(width 0)
					(fill yes)
				)
			)
		)
	)
	(footprint ""
		(layer "F.Cu")
		(at 263.728962 -367.448846)
		(property "Reference" "R2"
			(at 0 0 0)
			(layer "F.SilkS")
			(hide yes)
			(effects
				(font
					(size 1.27 1.27)
				)
			)
		)
		(property "Value" "3K83R2F-GP"
			(at 0.064008 -3.993896 0)
			(unlocked yes)
			(layer "F.Fab")
			(hide yes)
			(effects
				(font
					(size 1.016 1.016)
					(thickness 0.1524)
				)
			)
		)
		(property "Device Type" "R402H16"
			(at 0.064008 -5.517896 0)
			(unlocked yes)
			(layer "F.Fab")
			(hide yes)
			(effects
				(font
					(size 1.016 1.016)
					(thickness 0.1524)
				)
			)
		)
		(duplicate_pad_numbers_are_jumpers no)
		(fp_line
			(start -0.508 -0.9398)
			(end -0.508 0.9398)
			(stroke
				(width 0.1524)
				(type default)
			)
			(layer "F.SilkS")
		)
		(fp_line
			(start 0.508 -0.9398)
			(end -0.508 -0.9398)
			(stroke
				(width 0.1524)
				(type default)
			)
			(layer "F.SilkS")
		)
		(fp_rect
			(start -0.508 0.9398)
			(end 0.508 -0.9398)
			(stroke
				(width 0)
				(type default)
			)
			(fill no)
			(layer "F.CrtYd")
		)
		(fp_rect
			(start -0.508 0.9398)
			(end 0.508 -0.9398)
			(stroke
				(width 0)
				(type default)
			)
			(fill no)
			(layer "F.Fab")
		)
		(pad "1" smd custom
			(at 0 -0.4445)
			(size 0.1397 0.1397)
			(layers "F.Cu" "F.Mask" "F.Paste")
			(net "DPB_PWR_BTN_BUF_B")
			(options
				(clearance outline)
				(anchor circle)
			)
			(primitives
				(gr_poly
					(pts
						(arc
							(start -0.1778 -0.2794)
							(mid -0.249642 -0.249642)
							(end -0.2794 -0.1778)
						)
						(arc
							(start -0.2794 0.1778)
							(mid -0.249642 0.249642)
							(end -0.1778 0.2794)
						)
						(arc
							(start 0.1778 0.2794)
							(mid 0.249642 0.249642)
							(end 0.2794 0.1778)
						)
						(arc
							(start 0.2794 -0.1778)
							(mid 0.249642 -0.249642)
							(end 0.1778 -0.2794)
						)
					)
					(width 0)
					(fill yes)
				)
			)
		)
		(pad "2" smd custom
			(at 0 0.4445)
			(size 0.1397 0.1397)
			(layers "F.Cu" "F.Mask" "F.Paste")
			(net "GND")
			(options
				(clearance outline)
				(anchor circle)
			)
			(primitives
				(gr_poly
					(pts
						(arc
							(start -0.1778 -0.2794)
							(mid -0.249642 -0.249642)
							(end -0.2794 -0.1778)
						)
						(arc
							(start -0.2794 0.1778)
							(mid -0.249642 0.249642)
							(end -0.1778 0.2794)
						)
						(arc
							(start 0.1778 0.2794)
							(mid 0.249642 0.249642)
							(end 0.2794 0.1778)
						)
						(arc
							(start 0.2794 -0.1778)
							(mid 0.249642 -0.249642)
							(end 0.1778 -0.2794)
						)
					)
					(width 0)
					(fill yes)
				)
			)
		)
	)
	(footprint ""
		(layer "F.Cu")
		(at 128.93548 -244.990874 90)
		(property "Reference" "VIA7"
			(at 0 0 90)
			(layer "F.SilkS")
			(hide yes)
			(effects
				(font
					(size 1.27 1.27)
				)
			)
		)
		(property "Value" "100OHM-8L-2D36MM-L18-GP"
			(at 3.8989 0.5715 90)
			(unlocked yes)
			(layer "F.Fab")
			(hide yes)
			(effects
				(font
					(size 1.016 1.016)
					(thickness 0.1524)
				)
			)
		)
		(property "Device Type" "VIA-PCIE-4P-414097"
			(at 3.8989 -0.9525 90)
			(unlocked yes)
			(layer "F.Fab")
			(hide yes)
			(effects
				(font
					(size 1.016 1.016)
					(thickness 0.1524)
				)
			)
		)
		(duplicate_pad_numbers_are_jumpers no)
		(fp_rect
			(start -2.0701 0.4826)
			(end 2.0701 -0.4826)
			(stroke
				(width 0)
				(type default)
			)
			(fill no)
			(layer "F.CrtYd")
		)
		(fp_rect
			(start -2.0701 0.4826)
			(end 2.0701 -0.4826)
			(stroke
				(width 0)
				(type default)
			)
			(fill no)
			(layer "F.Fab")
		)
		(pad "1" thru_hole circle
			(at -1.5875 0 90)
			(size 0.508 0.508)
			(drill 0.254)
			(layers "*.Cu" "*.Mask")
			(remove_unused_layers no)
			(net "GND")
			(clearance 0.2286)
			(thermal_gap 0.2286)
		)
		(pad "2" thru_hole circle
			(at -0.5715 0 90)
			(size 0.508 0.508)
			(drill 0.254)
			(layers "*.Cu" "*.Mask")
			(remove_unused_layers no)
			(net "PHY_SCC_B_TO_DRV_B_3_DP")
			(clearance 0.2286)
			(thermal_gap 0.2286)
		)
		(pad "3" thru_hole circle
			(at 0.5715 0 90)
			(size 0.508 0.508)
			(drill 0.254)
			(layers "*.Cu" "*.Mask")
			(remove_unused_layers no)
			(net "PHY_SCC_B_TO_DRV_B_3_DN")
			(clearance 0.2286)
			(thermal_gap 0.2286)
		)
		(pad "4" thru_hole circle
			(at 1.5875 0 90)
			(size 0.508 0.508)
			(drill 0.254)
			(layers "*.Cu" "*.Mask")
			(remove_unused_layers no)
			(net "GND")
			(clearance 0.2286)
			(thermal_gap 0.2286)
		)
	)
)
